#ISCELL
  mstr_misc dns *
  *
#ISCELL
  pure_quanta quanta_title_block_c *
  *
#ISCELL
  standard offpage *
  page31_i1
#ISCELL
  logical_power universal_gnd *
  page31_i10
#CELL
  pure_quanta q_cap *
  page31_i11
#ISCELL
  logical_power universal_power *
  page31_i12
#ISCELL
  logical_power universal_gnd *
  page31_i16
#CELL
  pure_quanta q_cap *
  page31_i17
#ISCELL
  logical_power universal_power *
  page31_i18
#ISCELL
  standard offpage *
  page31_i19
#ISCELL
  standard offpage *
  page31_i2
#ISCELL
  standard offpage *
  page31_i20
#ISCELL
  standard offpage *
  page31_i21
#ISCELL
  standard offpage *
  page31_i22
#CELL
  pure_quanta nc7sb3157 *
  page31_i23
#CELL
  pure_quanta nc7sb3157 *
  page31_i24
#CELL
  pure_quanta q_res *
  page31_i25
#ISCELL
  logical_power universal_power *
  page31_i26
#CELL
  pure_quanta nc7sb3157 *
  page31_i27
#ISCELL
  standard offpage *
  page31_i28
#ISCELL
  standard offpage *
  page31_i3
#ISCELL
  logical_power universal_power *
  page31_i30
#CELL
  pure_quanta q_cap *
  page31_i31
#ISCELL
  logical_power universal_gnd *
  page31_i32
#ISCELL
  logical_power universal_gnd *
  page31_i33
#CELL
  pure_quanta nc7sb3157 *
  page31_i38
#ISCELL
  standard offpage *
  page31_i4
#ISCELL
  logical_power universal_gnd *
  page31_i43
#ISCELL
  logical_power universal_gnd *
  page31_i44
#CELL
  pure_quanta q_cap *
  page31_i45
#ISCELL
  logical_power universal_power *
  page31_i46
#ISCELL
  standard offpage *
  page31_i47
#ISCELL
  standard offpage *
  page31_i48
#ISCELL
  standard offpage *
  page31_i49
#ISCELL
  logical_power universal_gnd *
  page31_i52
#ISCELL
  logical_power universal_power *
  page31_i54
#ISCELL
  standard offpage *
  page31_i56
#ISCELL
  standard offpage *
  page31_i59
#CELL
  pure_quanta sconn3_212h9103gbr1 *
  page31_i61
#ISCELL
  standard offpage *
  page31_i62
#ISCELL
  standard offpage *
  page31_i63
#ISCELL
  standard offpage *
  page31_i68
#ISCELL
  standard offpage *
  page31_i69
#ISCELL
  logical_power universal_gnd *
  page31_i7
#CELL
  pure_quanta q_res *
  page31_i70
#CELL
  pure_quanta q_res *
  page31_i71
#CELL
  pure_quanta q_res *
  page31_i72
#CELL
  pure_quanta q_res *
  page31_i73
#CELL
  pure_quanta q_res *
  page31_i74
#CELL
  pure_quanta q_res *
  page31_i75
#CELL
  pure_quanta q_res *
  page31_i76
#CELL
  pure_quanta q_res *
  page31_i77
#CELL
  pure_quanta q_res *
  page31_i78
#CELL
  pure_quanta q_res *
  page31_i79
#CELL
  pure_quanta q_res *
  page31_i80
#ISCELL
  logical_power universal_power *
  page31_i81
#ISCELL
  logical_power universal_gnd *
  page31_i9
